# BASEBOARD_FAB2 (Tioga Pass) — schematic netlist excerpt (pin names and nets, part order shuffled) for the footprints in the layout excerpt that follows; sources: Cadence DE-HDL packaged netlist, KiCad conversion of Wiwynn_Tioga_Pass_MB.brd

R25W39  120R2F-GP  1%  pkg RCL_GP  page 151 : \1\ = BMC_M_A1 ; \2\ = P1V2_AUX_BMC
R25W118  RES  0.0 5% CHIP  pkg 0402  page 151 : A = BMC_M_PAR ; B = GND
C9R5  CAP  10UF 16V 10% X6S  pkg 0805  page 195 : A = P12V_PSU ; B = GND

(kicad_pcb
	(version 20260206)
	(generator "pcbnew")
	(generator_version "10.0")
	(general
		(thickness 1.6)
		(legacy_teardrops no)
	)
	(paper "A4")
	(title_block
		(title "Wiwynn_Tioga_Pass_MB.brd")
		(comment 1 "Tioga Pass / footprints 2620-2622 of 4770")
	)
	(layers
		(0 "F.Cu" signal "TOP")
		(4 "In1.Cu" signal "L2GND")
		(6 "In2.Cu" signal "L3")
		(8 "In3.Cu" signal "L4GND")
		(10 "In4.Cu" signal "L5")
		(12 "In5.Cu" signal "L6GND")
		(14 "In6.Cu" signal "L7VCC")
		(16 "In7.Cu" signal "L8VCC")
		(18 "In8.Cu" signal "L9GND")
		(20 "In9.Cu" signal "L10")
		(22 "In10.Cu" signal "L11GND")
		(24 "In11.Cu" signal "L12")
		(26 "In12.Cu" signal "L13GND")
		(2 "B.Cu" signal "BOTTOM")
		(9 "F.Adhes" user "F.Adhesive")
		(11 "B.Adhes" user "B.Adhesive")
		(13 "F.Paste" user "Package Geometry/Pastemask Top")
		(15 "B.Paste" user "Package Geometry/Pastemask Bottom")
		(5 "F.SilkS" user "Ref Des/Silkscreen Top")
		(7 "B.SilkS" user "Ref Des/Silkscreen Bottom")
		(1 "F.Mask" user "Board Geometry/Soldermask Top")
		(3 "B.Mask" user "Board Geometry/Soldermask Bottom")
		(17 "Dwgs.User" user "User.Drawings")
		(19 "Cmts.User" user "User.Comments")
		(21 "Eco1.User" user "User.Eco1")
		(23 "Eco2.User" user "User.Eco2")
		(25 "Edge.Cuts" user "Board Geometry/Outline")
		(27 "Margin" user)
		(31 "F.CrtYd" user "Package Geometry/Place Bound Top")
		(29 "B.CrtYd" user "Package Geometry/Place Bound Bottom")
		(35 "F.Fab" user "Ref Des/Assembly Top")
		(33 "B.Fab" user "Ref Des/Assembly Bottom")
	)
	(footprint ""
		(layer "B.Cu")
		(at 437.690006 -43.54195 180)
		(property "Reference" "R25W39"
			(at 0 0 0)
			(layer "B.SilkS")
			(hide yes)
			(effects
				(font
					(size 1.27 1.27)
				)
				(justify mirror)
			)
		)
		(property "Value" "*"
			(at -0.064008 -4.108196 180)
			(unlocked yes)
			(layer "B.Fab")
			(hide yes)
			(effects
				(font
					(size 1.27 1.016)
					(thickness 0.1524)
				)
				(justify mirror)
			)
		)
		(property "Device Type" "120R2F-GP_RCL_GP-120R2F-GP,64.A"
			(at -0.064008 -5.632196 180)
			(unlocked yes)
			(layer "B.Fab")
			(hide yes)
			(effects
				(font
					(size 1.27 1.016)
					(thickness 0.1524)
				)
				(justify mirror)
			)
		)
		(duplicate_pad_numbers_are_jumpers no)
		(fp_line
			(start 0.508 -0.9398)
			(end 0.508 0.9398)
			(stroke
				(width 0.1524)
				(type default)
			)
			(layer "B.SilkS")
		)
		(fp_line
			(start -0.508 -0.9398)
			(end 0.508 -0.9398)
			(stroke
				(width 0.1524)
				(type default)
			)
			(layer "B.SilkS")
		)
		(fp_rect
			(start 0.508 0.9398)
			(end -0.508 -0.9398)
			(stroke
				(width 0)
				(type default)
			)
			(fill no)
			(layer "B.CrtYd")
		)
		(fp_rect
			(start 0.508 0.9398)
			(end -0.508 -0.9398)
			(stroke
				(width 0)
				(type default)
			)
			(fill no)
			(layer "B.Fab")
		)
		(pad "1" smd custom
			(at 0 -0.4445)
			(size 0.1397 0.1397)
			(layers "B.Cu" "B.Mask" "B.Paste")
			(net "BMC_M_A1")
			(options
				(clearance outline)
				(anchor circle)
			)
			(primitives
				(gr_poly
					(pts
						(arc
							(start -0.1778 0.2794)
							(mid -0.249642 0.249642)
							(end -0.2794 0.1778)
						)
						(arc
							(start -0.2794 -0.1778)
							(mid -0.249642 -0.249642)
							(end -0.1778 -0.2794)
						)
						(arc
							(start 0.1778 -0.2794)
							(mid 0.249642 -0.249642)
							(end 0.2794 -0.1778)
						)
						(arc
							(start 0.2794 0.1778)
							(mid 0.249642 0.249642)
							(end 0.1778 0.2794)
						)
					)
					(width 0)
					(fill yes)
				)
			)
		)
		(pad "2" smd custom
			(at 0 0.4445)
			(size 0.1397 0.1397)
			(layers "B.Cu" "B.Mask" "B.Paste")
			(net "P1V2_AUX_BMC")
			(options
				(clearance outline)
				(anchor circle)
			)
			(primitives
				(gr_poly
					(pts
						(arc
							(start -0.1778 0.2794)
							(mid -0.249642 0.249642)
							(end -0.2794 0.1778)
						)
						(arc
							(start -0.2794 -0.1778)
							(mid -0.249642 -0.249642)
							(end -0.1778 -0.2794)
						)
						(arc
							(start 0.1778 -0.2794)
							(mid 0.249642 -0.249642)
							(end 0.2794 -0.1778)
						)
						(arc
							(start 0.2794 0.1778)
							(mid 0.249642 0.249642)
							(end 0.1778 0.2794)
						)
					)
					(width 0)
					(fill yes)
				)
			)
		)
	)
	(footprint ""
		(layer "B.Cu")
		(at 444.062866 -38.39591 90)
		(property "Reference" "R25W118"
			(at 0.8382 -0.67818 90)
			(unlocked yes)
			(layer "B.SilkS")
			(effects
				(font
					(size 0.4064 0.254)
					(thickness 0.1524)
				)
				(justify left mirror)
			)
		)
		(property "Value" ""
			(at 0 0 90)
			(layer "B.Fab")
			(effects
				(font
					(size 1.27 1.27)
				)
				(justify mirror)
			)
		)
		(duplicate_pad_numbers_are_jumpers no)
		(fp_poly
			(pts
				(xy 0.2794 -0.1016) (xy -0.2794 -0.1016) (xy -0.2794 0.9906) (xy 0.2794 0.9906)
			)
			(stroke
				(width 0)
				(type default)
			)
			(fill no)
			(layer "B.CrtYd")
		)
		(fp_line
			(start 0.2794 -0.1016)
			(end 0.2794 0.9906)
			(stroke
				(width 0.1)
				(type default)
			)
			(layer "B.Fab")
		)
		(fp_line
			(start -0.2794 -0.1016)
			(end 0.2794 -0.1016)
			(stroke
				(width 0.1)
				(type default)
			)
			(layer "B.Fab")
		)
		(fp_line
			(start 0.2794 0.9906)
			(end -0.2794 0.9906)
			(stroke
				(width 0.1)
				(type default)
			)
			(layer "B.Fab")
		)
		(fp_line
			(start -0.2794 0.9906)
			(end -0.2794 -0.1016)
			(stroke
				(width 0.1)
				(type default)
			)
			(layer "B.Fab")
		)
		(pad "1" smd rect
			(at 0 0 270)
			(size 0.508 0.508)
			(layers "B.Cu" "B.Mask" "B.Paste")
			(net "BMC_M_PAR")
		)
		(pad "2" smd rect
			(at 0 0.889 270)
			(size 0.508 0.508)
			(layers "B.Cu" "B.Mask" "B.Paste")
			(net "GND")
		)
		(zone
			(layer "B.Cu")
			(hatch none 0.5)
			(connect_pads
				(clearance 0)
			)
			(min_thickness 0.25)
			(keepout
				(tracks allowed)
				(vias not_allowed)
				(pads allowed)
				(copperpour not_allowed)
				(footprints allowed)
			)
			(placement
				(enabled no)
				(sheetname "")
			)
			(fill
				(thermal_gap 0.5)
				(thermal_bridge_width 0.5)
				(island_removal_mode 0)
			)
			(polygon
				(pts
					(xy 444.316866 -38.64991) (xy 444.316866 -38.14191) (xy 444.697866 -38.14191) (xy 444.697866 -38.64991)
				)
			)
		)
		(zone
			(layer "B.Cu")
			(hatch none 0.5)
			(connect_pads
				(clearance 0)
			)
			(min_thickness 0.25)
			(keepout
				(tracks not_allowed)
				(vias allowed)
				(pads allowed)
				(copperpour not_allowed)
				(footprints allowed)
			)
			(placement
				(enabled no)
				(sheetname "")
			)
			(fill
				(thermal_gap 0.5)
				(thermal_bridge_width 0.5)
				(island_removal_mode 0)
			)
			(polygon
				(pts
					(xy 444.697866 -38.64991) (xy 444.697866 -38.14191) (xy 444.316866 -38.14191) (xy 444.316866 -38.64991)
				)
			)
		)
	)
	(footprint ""
		(layer "B.Cu")
		(at 2.8702 -61.6712 -90)
		(property "Reference" "C9R5"
			(at 0 0 90)
			(layer "B.SilkS")
			(hide yes)
			(effects
				(font
					(size 1.27 1.27)
				)
				(justify mirror)
			)
		)
		(property "Value" ""
			(at 0 0 90)
			(layer "B.Fab")
			(effects
				(font
					(size 1.27 1.27)
				)
				(justify mirror)
			)
		)
		(duplicate_pad_numbers_are_jumpers no)
		(fp_rect
			(start -0.7239 -0.2159)
			(end 0.7239 1.9939)
			(stroke
				(width 0)
				(type default)
			)
			(fill no)
			(layer "B.CrtYd")
		)
		(fp_line
			(start -0.7239 1.9939)
			(end -0.7239 -0.2159)
			(stroke
				(width 0.1)
				(type default)
			)
			(layer "B.Fab")
		)
		(fp_line
			(start 0.7239 1.9939)
			(end -0.7239 1.9939)
			(stroke
				(width 0.1)
				(type default)
			)
			(layer "B.Fab")
		)
		(fp_line
			(start -0.7239 -0.2159)
			(end 0.7239 -0.2159)
			(stroke
				(width 0.1)
				(type default)
			)
			(layer "B.Fab")
		)
		(fp_line
			(start 0.7239 -0.2159)
			(end 0.7239 1.9939)
			(stroke
				(width 0.1)
				(type default)
			)
			(layer "B.Fab")
		)
		(pad "1" smd rect
			(at 0 0 90)
			(size 1.27 1.016)
			(layers "B.Cu" "B.Mask" "B.Paste")
			(net "P12V_PSU")
		)
		(pad "2" smd rect
			(at 0 1.778 90)
			(size 1.27 1.016)
			(layers "B.Cu" "B.Mask" "B.Paste")
			(net "GND")
		)
		(zone
			(layer "B.Cu")
			(hatch none 0.5)
			(connect_pads
				(clearance 0)
			)
			(min_thickness 0.25)
			(keepout
				(tracks not_allowed)
				(vias allowed)
				(pads allowed)
				(copperpour not_allowed)
				(footprints allowed)
			)
			(placement
				(enabled no)
				(sheetname "")
			)
			(fill
				(thermal_gap 0.5)
				(thermal_bridge_width 0.5)
				(island_removal_mode 0)
			)
			(polygon
				(pts
					(xy 2.3622 -62.3062) (xy 1.6002 -62.3062) (xy 1.6002 -61.0362) (xy 2.3622 -61.0362)
				)
			)
		)
	)
)
